# S9S_MB_2U (Grand Teton) — schematic netlist excerpt (pin names and nets, part order shuffled) for the footprints in the layout excerpt that follows; sources: Cadence DE-HDL packaged netlist, KiCad conversion of 03242023_DA0F0TMBIJ0_F0T_Motherboard_J_brd_V01_OCP.brd

C2369  Q_CAP  1UF 25V 10% EMPTY  pkg C0402  page 224 : A = FM_AC_PWR_BTN_R_N ; B = GND
PC635  Q_CAP  1UF 16V 10% X6S  pkg C0402  page 279 : A = SW_P12V_PVCCINFAON_CPU0_FLT ; B = GND

(kicad_pcb
	(version 20260206)
	(generator "pcbnew")
	(generator_version "10.0")
	(general
		(thickness 1.6)
		(legacy_teardrops no)
	)
	(paper "A4")
	(title_block
		(title "03242023_DA0F0TMBIJ0_F0T_Motherboard_J_brd_V01_OCP.brd")
		(comment 1 "Grand Teton / footprints 1377-1378 of 6105")
	)
	(layers
		(0 "F.Cu" signal "TOP")
		(4 "In1.Cu" signal "GND")
		(6 "In2.Cu" signal "IN1")
		(8 "In3.Cu" signal "GND1")
		(10 "In4.Cu" signal "IN2")
		(12 "In5.Cu" signal "GND2")
		(14 "In6.Cu" signal "IN3")
		(16 "In7.Cu" signal "GND3")
		(18 "In8.Cu" signal "VCC")
		(20 "In9.Cu" signal "VCC1")
		(22 "In10.Cu" signal "GND4")
		(24 "In11.Cu" signal "IN4")
		(26 "In12.Cu" signal "GND5")
		(28 "In13.Cu" signal "IN5")
		(30 "In14.Cu" signal "GND6")
		(32 "In15.Cu" signal "IN6")
		(34 "In16.Cu" signal "GND7")
		(2 "B.Cu" signal "BOTTOM")
		(9 "F.Adhes" user "F.Adhesive")
		(11 "B.Adhes" user "B.Adhesive")
		(13 "F.Paste" user "Package Geometry/Pastemask Top")
		(15 "B.Paste" user "Package Geometry/Pastemask Bottom")
		(5 "F.SilkS" user "Ref Des/Silkscreen Top")
		(7 "B.SilkS" user "Ref Des/Silkscreen Bottom")
		(1 "F.Mask" user "Board Geometry/Soldermask Top")
		(3 "B.Mask" user "Board Geometry/Soldermask Bottom")
		(17 "Dwgs.User" user "User.Drawings")
		(19 "Cmts.User" user "User.Comments")
		(21 "Eco1.User" user "User.Eco1")
		(23 "Eco2.User" user "User.Eco2")
		(25 "Edge.Cuts" user "Board Geometry/Outline")
		(27 "Margin" user)
		(31 "F.CrtYd" user "Package Geometry/Place Bound Top")
		(29 "B.CrtYd" user "Package Geometry/Place Bound Bottom")
		(35 "F.Fab" user "Ref Des/Assembly Top")
		(33 "B.Fab" user "Ref Des/Assembly Bottom")
	)
	(footprint ""
		(layer "F.Cu")
		(at 421.927528 -157.990286 -90)
		(property "Reference" "PC635"
			(at 0 0 270)
			(layer "F.SilkS")
			(hide yes)
			(effects
				(font
					(size 1.27 1.27)
				)
			)
		)
		(property "Value" ""
			(at 0 0 270)
			(layer "F.Fab")
			(effects
				(font
					(size 1.27 1.27)
				)
			)
		)
		(duplicate_pad_numbers_are_jumpers no)
		(fp_line
			(start -0.7874 0.4064)
			(end -0.7874 -0.4064)
			(stroke
				(width 0.1524)
				(type default)
			)
			(layer "F.SilkS")
		)
		(fp_line
			(start 0.7874 0.4064)
			(end -0.7874 0.4064)
			(stroke
				(width 0.1524)
				(type default)
			)
			(layer "F.SilkS")
		)
		(fp_line
			(start -0.7874 -0.4064)
			(end 0.7874 -0.4064)
			(stroke
				(width 0.1524)
				(type default)
			)
			(layer "F.SilkS")
		)
		(fp_line
			(start 0.7874 -0.4064)
			(end 0.7874 0.4064)
			(stroke
				(width 0.1524)
				(type default)
			)
			(layer "F.SilkS")
		)
		(fp_line
			(start -0.67945 0.3048)
			(end -0.67945 -0.305054)
			(stroke
				(width 0.1)
				(type default)
			)
			(layer "F.Fab")
		)
		(fp_line
			(start -0.12065 0.3048)
			(end -0.67945 0.3048)
			(stroke
				(width 0.1)
				(type default)
			)
			(layer "F.Fab")
		)
		(fp_line
			(start 0.120396 0.3048)
			(end 0.120396 0.2794)
			(stroke
				(width 0.1)
				(type default)
			)
			(layer "F.Fab")
		)
		(fp_line
			(start 0.67945 0.3048)
			(end 0.120396 0.3048)
			(stroke
				(width 0.1)
				(type default)
			)
			(layer "F.Fab")
		)
		(fp_line
			(start -0.12065 0.2794)
			(end -0.12065 0.3048)
			(stroke
				(width 0.1)
				(type default)
			)
			(layer "F.Fab")
		)
		(fp_line
			(start 0.120396 0.2794)
			(end -0.12065 0.2794)
			(stroke
				(width 0.1)
				(type default)
			)
			(layer "F.Fab")
		)
		(fp_line
			(start -0.12065 -0.2794)
			(end 0.12065 -0.2794)
			(stroke
				(width 0.1)
				(type default)
			)
			(layer "F.Fab")
		)
		(fp_line
			(start 0.12065 -0.2794)
			(end 0.12065 -0.3048)
			(stroke
				(width 0.1)
				(type default)
			)
			(layer "F.Fab")
		)
		(fp_line
			(start 0.12065 -0.3048)
			(end 0.67945 -0.3048)
			(stroke
				(width 0.1)
				(type default)
			)
			(layer "F.Fab")
		)
		(fp_line
			(start 0.67945 -0.3048)
			(end 0.67945 0.3048)
			(stroke
				(width 0.1)
				(type default)
			)
			(layer "F.Fab")
		)
		(fp_line
			(start -0.67945 -0.305054)
			(end -0.12065 -0.305054)
			(stroke
				(width 0.1)
				(type default)
			)
			(layer "F.Fab")
		)
		(fp_line
			(start -0.12065 -0.305054)
			(end -0.12065 -0.2794)
			(stroke
				(width 0.1)
				(type default)
			)
			(layer "F.Fab")
		)
		(pad "1" smd circle
			(at -0.40005 0 270)
			(size 0 0)
			(layers "F.Cu" "F.Mask" "F.Paste")
			(net "SW_P12V_PVCCINFAON_CPU0_FLT")
		)
		(pad "2" smd circle
			(at 0.40005 0 270)
			(size 0 0)
			(layers "F.Cu" "F.Mask" "F.Paste")
			(net "GND")
		)
	)
	(footprint ""
		(layer "F.Cu")
		(at 216.1286 -120.142 180)
		(property "Reference" "C2369"
			(at 0 0 180)
			(layer "F.SilkS")
			(hide yes)
			(effects
				(font
					(size 1.27 1.27)
				)
			)
		)
		(property "Value" ""
			(at 0 0 180)
			(layer "F.Fab")
			(effects
				(font
					(size 1.27 1.27)
				)
			)
		)
		(duplicate_pad_numbers_are_jumpers no)
		(fp_line
			(start 0.7874 0.4064)
			(end -0.7874 0.4064)
			(stroke
				(width 0.1524)
				(type default)
			)
			(layer "F.SilkS")
		)
		(fp_line
			(start 0.7874 -0.4064)
			(end 0.7874 0.4064)
			(stroke
				(width 0.1524)
				(type default)
			)
			(layer "F.SilkS")
		)
		(fp_line
			(start -0.7874 0.4064)
			(end -0.7874 -0.4064)
			(stroke
				(width 0.1524)
				(type default)
			)
			(layer "F.SilkS")
		)
		(fp_line
			(start -0.7874 -0.4064)
			(end 0.7874 -0.4064)
			(stroke
				(width 0.1524)
				(type default)
			)
			(layer "F.SilkS")
		)
		(fp_line
			(start 0.67945 0.3048)
			(end 0.120396 0.3048)
			(stroke
				(width 0.1)
				(type default)
			)
			(layer "F.Fab")
		)
		(fp_line
			(start 0.67945 -0.3048)
			(end 0.67945 0.3048)
			(stroke
				(width 0.1)
				(type default)
			)
			(layer "F.Fab")
		)
		(fp_line
			(start 0.12065 -0.2794)
			(end 0.12065 -0.3048)
			(stroke
				(width 0.1)
				(type default)
			)
			(layer "F.Fab")
		)
		(fp_line
			(start 0.12065 -0.3048)
			(end 0.67945 -0.3048)
			(stroke
				(width 0.1)
				(type default)
			)
			(layer "F.Fab")
		)
		(fp_line
			(start 0.120396 0.3048)
			(end 0.120396 0.2794)
			(stroke
				(width 0.1)
				(type default)
			)
			(layer "F.Fab")
		)
		(fp_line
			(start 0.120396 0.2794)
			(end -0.12065 0.2794)
			(stroke
				(width 0.1)
				(type default)
			)
			(layer "F.Fab")
		)
		(fp_line
			(start -0.12065 0.3048)
			(end -0.67945 0.3048)
			(stroke
				(width 0.1)
				(type default)
			)
			(layer "F.Fab")
		)
		(fp_line
			(start -0.12065 0.2794)
			(end -0.12065 0.3048)
			(stroke
				(width 0.1)
				(type default)
			)
			(layer "F.Fab")
		)
		(fp_line
			(start -0.12065 -0.2794)
			(end 0.12065 -0.2794)
			(stroke
				(width 0.1)
				(type default)
			)
			(layer "F.Fab")
		)
		(fp_line
			(start -0.12065 -0.305054)
			(end -0.12065 -0.2794)
			(stroke
				(width 0.1)
				(type default)
			)
			(layer "F.Fab")
		)
		(fp_line
			(start -0.67945 0.3048)
			(end -0.67945 -0.305054)
			(stroke
				(width 0.1)
				(type default)
			)
			(layer "F.Fab")
		)
		(fp_line
			(start -0.67945 -0.305054)
			(end -0.12065 -0.305054)
			(stroke
				(width 0.1)
				(type default)
			)
			(layer "F.Fab")
		)
		(pad "1" smd circle
			(at -0.40005 0 180)
			(size 0 0)
			(layers "F.Cu" "F.Mask" "F.Paste")
			(net "FM_AC_PWR_BTN_R_N")
		)
		(pad "2" smd circle
			(at 0.40005 0 180)
			(size 0 0)
			(layers "F.Cu" "F.Mask" "F.Paste")
			(net "GND")
		)
	)
)
